# BASEBOARD_FAB2 (Tioga Pass) — schematic netlist excerpt (pin names and nets, part order shuffled) for the footprints in the layout excerpt that follows; sources: Cadence DE-HDL packaged netlist, KiCad conversion of Wiwynn_Tioga_Pass_MB.brd

C7P8  CAP  100UF 4V 20% X5R  pkg 0805  page 76 : A = PVCCMCP_CPU1 ; B = GND
C6R11  CAP  10UF 16V 10% X6S  pkg 0805  page 202 : A = VR_FET_SW_P12V_STBY_PVCCIN_CPU0 ; B = GND
C7B17  CAP_A  22.0UF 4V 20% X6S  pkg 0603V  page 131 : A = P1V05_PCH_STBY ; B = GND

(kicad_pcb
	(version 20260206)
	(generator "pcbnew")
	(generator_version "10.0")
	(general
		(thickness 1.6)
		(legacy_teardrops no)
	)
	(paper "A4")
	(title_block
		(title "Wiwynn_Tioga_Pass_MB.brd")
		(comment 1 "Tioga Pass / footprints 3077-3079 of 4770")
	)
	(layers
		(0 "F.Cu" signal "TOP")
		(4 "In1.Cu" signal "L2GND")
		(6 "In2.Cu" signal "L3")
		(8 "In3.Cu" signal "L4GND")
		(10 "In4.Cu" signal "L5")
		(12 "In5.Cu" signal "L6GND")
		(14 "In6.Cu" signal "L7VCC")
		(16 "In7.Cu" signal "L8VCC")
		(18 "In8.Cu" signal "L9GND")
		(20 "In9.Cu" signal "L10")
		(22 "In10.Cu" signal "L11GND")
		(24 "In11.Cu" signal "L12")
		(26 "In12.Cu" signal "L13GND")
		(2 "B.Cu" signal "BOTTOM")
		(9 "F.Adhes" user "F.Adhesive")
		(11 "B.Adhes" user "B.Adhesive")
		(13 "F.Paste" user "Package Geometry/Pastemask Top")
		(15 "B.Paste" user "Package Geometry/Pastemask Bottom")
		(5 "F.SilkS" user "Ref Des/Silkscreen Top")
		(7 "B.SilkS" user "Ref Des/Silkscreen Bottom")
		(1 "F.Mask" user "Board Geometry/Soldermask Top")
		(3 "B.Mask" user "Board Geometry/Soldermask Bottom")
		(17 "Dwgs.User" user "User.Drawings")
		(19 "Cmts.User" user "User.Comments")
		(21 "Eco1.User" user "User.Eco1")
		(23 "Eco2.User" user "User.Eco2")
		(25 "Edge.Cuts" user "Board Geometry/Outline")
		(27 "Margin" user)
		(31 "F.CrtYd" user "Package Geometry/Place Bound Top")
		(29 "B.CrtYd" user "Package Geometry/Place Bound Bottom")
		(35 "F.Fab" user "Ref Des/Assembly Top")
		(33 "B.Fab" user "Ref Des/Assembly Bottom")
	)
	(footprint ""
		(layer "B.Cu")
		(at 197.848728 -58.428382 90)
		(property "Reference" "C6R11"
			(at 0 0 90)
			(layer "B.SilkS")
			(hide yes)
			(effects
				(font
					(size 1.27 1.27)
				)
				(justify mirror)
			)
		)
		(property "Value" ""
			(at 0 0 90)
			(layer "B.Fab")
			(effects
				(font
					(size 1.27 1.27)
				)
				(justify mirror)
			)
		)
		(duplicate_pad_numbers_are_jumpers no)
		(fp_rect
			(start 0.7239 1.9939)
			(end -0.7239 -0.2159)
			(stroke
				(width 0)
				(type default)
			)
			(fill no)
			(layer "B.CrtYd")
		)
		(fp_line
			(start 0.7239 -0.2159)
			(end 0.7239 1.9939)
			(stroke
				(width 0.1)
				(type default)
			)
			(layer "B.Fab")
		)
		(fp_line
			(start -0.7239 -0.2159)
			(end 0.7239 -0.2159)
			(stroke
				(width 0.1)
				(type default)
			)
			(layer "B.Fab")
		)
		(fp_line
			(start 0.7239 1.9939)
			(end -0.7239 1.9939)
			(stroke
				(width 0.1)
				(type default)
			)
			(layer "B.Fab")
		)
		(fp_line
			(start -0.7239 1.9939)
			(end -0.7239 -0.2159)
			(stroke
				(width 0.1)
				(type default)
			)
			(layer "B.Fab")
		)
		(pad "1" smd rect
			(at 0 0 270)
			(size 1.27 1.016)
			(layers "B.Cu" "B.Mask" "B.Paste")
			(net "VR_FET_SW_P12V_STBY_PVCCIN_CPU0")
		)
		(pad "2" smd rect
			(at 0 1.778 270)
			(size 1.27 1.016)
			(layers "B.Cu" "B.Mask" "B.Paste")
			(net "GND")
		)
		(zone
			(layer "B.Cu")
			(hatch none 0.5)
			(connect_pads
				(clearance 0)
			)
			(min_thickness 0.25)
			(keepout
				(tracks not_allowed)
				(vias allowed)
				(pads allowed)
				(copperpour not_allowed)
				(footprints allowed)
			)
			(placement
				(enabled no)
				(sheetname "")
			)
			(fill
				(thermal_gap 0.5)
				(thermal_bridge_width 0.5)
				(island_removal_mode 0)
			)
			(polygon
				(pts
					(xy 199.118728 -59.063382) (xy 198.356728 -59.063382) (xy 198.356728 -57.793382) (xy 199.118728 -57.793382)
				)
			)
		)
	)
	(footprint ""
		(layer "B.Cu")
		(at 111.836454 -77.82814)
		(property "Reference" "C7P8"
			(at 0 0 0)
			(layer "B.SilkS")
			(hide yes)
			(effects
				(font
					(size 1.27 1.27)
				)
				(justify mirror)
			)
		)
		(property "Value" ""
			(at 0 0 0)
			(layer "B.Fab")
			(effects
				(font
					(size 1.27 1.27)
				)
				(justify mirror)
			)
		)
		(duplicate_pad_numbers_are_jumpers no)
		(fp_poly
			(pts
				(xy 0.7239 -0.2159) (xy -0.7239 -0.2159) (xy -0.7239 1.9939) (xy 0.7239 1.9939)
			)
			(stroke
				(width 0)
				(type default)
			)
			(fill no)
			(layer "B.CrtYd")
		)
		(fp_line
			(start -0.7239 -0.2159)
			(end 0.7239 -0.2159)
			(stroke
				(width 0.1)
				(type default)
			)
			(layer "B.Fab")
		)
		(fp_line
			(start -0.7239 1.9939)
			(end -0.7239 -0.2159)
			(stroke
				(width 0.1)
				(type default)
			)
			(layer "B.Fab")
		)
		(fp_line
			(start 0.7239 -0.2159)
			(end 0.7239 1.9939)
			(stroke
				(width 0.1)
				(type default)
			)
			(layer "B.Fab")
		)
		(fp_line
			(start 0.7239 1.9939)
			(end -0.7239 1.9939)
			(stroke
				(width 0.1)
				(type default)
			)
			(layer "B.Fab")
		)
		(pad "1" smd rect
			(at 0 0 180)
			(size 1.27 1.016)
			(layers "B.Cu" "B.Mask" "B.Paste")
			(net "PVCCMCP_CPU1")
		)
		(pad "2" smd rect
			(at 0 1.778 180)
			(size 1.27 1.016)
			(layers "B.Cu" "B.Mask" "B.Paste")
			(net "GND")
		)
		(zone
			(layer "B.Cu")
			(hatch none 0.5)
			(connect_pads
				(clearance 0)
			)
			(min_thickness 0.25)
			(keepout
				(tracks not_allowed)
				(vias allowed)
				(pads allowed)
				(copperpour not_allowed)
				(footprints allowed)
			)
			(placement
				(enabled no)
				(sheetname "")
			)
			(fill
				(thermal_gap 0.5)
				(thermal_bridge_width 0.5)
				(island_removal_mode 0)
			)
			(polygon
				(pts
					(xy 112.471454 -77.32014) (xy 111.201454 -77.32014) (xy 111.201454 -76.55814) (xy 112.471454 -76.55814)
				)
			)
		)
	)
	(footprint ""
		(layer "B.Cu")
		(at 399.182336 -141.226286 180)
		(property "Reference" "C7B17"
			(at 0 0 0)
			(layer "B.SilkS")
			(hide yes)
			(effects
				(font
					(size 1.27 1.27)
				)
				(justify mirror)
			)
		)
		(property "Value" ""
			(at 0 0 0)
			(layer "B.Fab")
			(effects
				(font
					(size 1.27 1.27)
				)
				(justify mirror)
			)
		)
		(duplicate_pad_numbers_are_jumpers no)
		(fp_rect
			(start 0.4953 1.6002)
			(end -0.4953 -0.2032)
			(stroke
				(width 0)
				(type default)
			)
			(fill no)
			(layer "B.CrtYd")
		)
		(fp_line
			(start 0.4953 1.6002)
			(end 0.4953 -0.2032)
			(stroke
				(width 0.1)
				(type default)
			)
			(layer "B.Fab")
		)
		(fp_line
			(start 0.4953 -0.2032)
			(end -0.4953 -0.2032)
			(stroke
				(width 0.1)
				(type default)
			)
			(layer "B.Fab")
		)
		(fp_line
			(start -0.4953 1.6002)
			(end 0.4953 1.6002)
			(stroke
				(width 0.1)
				(type default)
			)
			(layer "B.Fab")
		)
		(fp_line
			(start -0.4953 -0.2032)
			(end -0.4953 1.6002)
			(stroke
				(width 0.1)
				(type default)
			)
			(layer "B.Fab")
		)
		(pad "1" smd rect
			(at 0 0)
			(size 0.762 0.889)
			(layers "B.Cu" "B.Mask" "B.Paste")
			(net "P1V05_PCH_STBY")
		)
		(pad "2" smd rect
			(at 0 1.397)
			(size 0.762 0.889)
			(layers "B.Cu" "B.Mask" "B.Paste")
			(net "GND")
		)
		(zone
			(layer "B.Cu")
			(hatch none 0.5)
			(connect_pads
				(clearance 0)
			)
			(min_thickness 0.25)
			(keepout
				(tracks not_allowed)
				(vias allowed)
				(pads allowed)
				(copperpour not_allowed)
				(footprints allowed)
			)
			(placement
				(enabled no)
				(sheetname "")
			)
			(fill
				(thermal_gap 0.5)
				(thermal_bridge_width 0.5)
				(island_removal_mode 0)
			)
			(polygon
				(pts
					(xy 398.801336 -142.178786) (xy 398.801336 -141.670786) (xy 399.563336 -141.670786) (xy 399.563336 -142.178786)
				)
			)
		)
	)
)
